(kicad_pcb
	(version 20260206)
	(generator "pcbnew")
	(generator_version "10.0")
	(general
		(thickness 1.6)
		(legacy_teardrops no)
	)
	(paper "A4")
	(title_block
		(title "fcb — Lightning_FCB_BRD.brd")
		(comment 1 "Lightning (Wiwynn / Facebook NVMe JBOF) / footprints 223-226 of 495")
	)
	(layers
		(0 "F.Cu" signal "TOP")
		(4 "In1.Cu" signal "L2GND")
		(6 "In2.Cu" signal "L3VCC")
		(2 "B.Cu" signal "BOTTOM")
		(9 "F.Adhes" user "F.Adhesive")
		(11 "B.Adhes" user "B.Adhesive")
		(13 "F.Paste" user "Package Geometry/Pastemask Top")
		(15 "B.Paste" user "Package Geometry/Pastemask Bottom")
		(5 "F.SilkS" user "Ref Des/Silkscreen Top")
		(7 "B.SilkS" user "Ref Des/Silkscreen Bottom")
		(1 "F.Mask" user "Board Geometry/Soldermask Top")
		(3 "B.Mask" user "Board Geometry/Soldermask Bottom")
		(17 "Dwgs.User" user "User.Drawings")
		(19 "Cmts.User" user "User.Comments")
		(21 "Eco1.User" user "User.Eco1")
		(23 "Eco2.User" user "User.Eco2")
		(25 "Edge.Cuts" user "Board Geometry/Outline")
		(27 "Margin" user)
		(31 "F.CrtYd" user "Package Geometry/Place Bound Top")
		(29 "B.CrtYd" user "Package Geometry/Place Bound Bottom")
		(35 "F.Fab" user "Ref Des/Assembly Top")
		(33 "B.Fab" user "Ref Des/Assembly Bottom")
	)
	(footprint ""
		(layer "F.Cu")
		(at 6.999986 -159.999934)
		(property "Reference" "H7"
			(at 0 0 0)
			(layer "F.SilkS")
			(hide yes)
			(effects
				(font
					(size 1.27 1.27)
				)
			)
		)
		(property "Value" "HOLE315R138"
			(at 0 -7.0612 0)
			(unlocked yes)
			(layer "F.Fab")
			(hide yes)
			(effects
				(font
					(size 1.016 1.016)
					(thickness 0.1524)
				)
			)
		)
		(property "Device Type" "HOLE315R138"
			(at 0 -8.5852 0)
			(unlocked yes)
			(layer "F.Fab")
			(hide yes)
			(effects
				(font
					(size 1.016 1.016)
					(thickness 0.1524)
				)
			)
		)
		(duplicate_pad_numbers_are_jumpers no)
		(fp_poly
			(pts
				(xy 0 4.3053) (xy -0.13462 4.30276) (xy -0.27051 4.29641) (xy -0.40513 4.28625) (xy -0.53975 4.27101)
				(xy -0.6731 4.25196) (xy -0.80645 4.2291) (xy -0.9398 4.20116) (xy -1.07061 4.17068) (xy -1.20142 4.13385)
				(xy -1.33096 4.09448) (xy -1.45796 4.0513) (xy -1.58496 4.00304) (xy -1.70942 3.95097) (xy -1.83261 3.89509)
				(xy -1.95453 3.83667) (xy -2.07391 3.77317) (xy -2.19202 3.70586) (xy -2.30632 3.63474) (xy -2.41935 3.56108)
				(xy -2.53111 3.48361) (xy -2.63906 3.40233) (xy -2.74447 3.31724) (xy -2.84734 3.22961) (xy -2.94767 3.13817)
				(xy -3.04419 3.04419) (xy -3.13817 2.94767) (xy -3.22961 2.84734) (xy -3.31724 2.74447) (xy -3.40233 2.63906)
				(xy -3.48361 2.53111) (xy -3.56108 2.41935) (xy -3.63474 2.30632) (xy -3.70586 2.19202) (xy -3.77317 2.07391)
				(xy -3.83667 1.95453) (xy -3.89509 1.83261) (xy -3.95097 1.70942) (xy -4.00304 1.58496) (xy -4.0513 1.45796)
				(xy -4.09448 1.33096) (xy -4.13385 1.20142) (xy -4.17068 1.07061) (xy -4.20116 0.9398) (xy -4.2291 0.80645)
				(xy -4.25196 0.6731) (xy -4.27101 0.53975) (xy -4.28625 0.40513) (xy -4.29641 0.27051) (xy -4.30276 0.13462)
				(xy -4.3053 0) (xy -4.30276 -0.13462) (xy -4.29641 -0.27051) (xy -4.28625 -0.40513) (xy -4.27101 -0.53975)
				(xy -4.25196 -0.6731) (xy -4.2291 -0.80645) (xy -4.20116 -0.9398) (xy -4.17068 -1.07061) (xy -4.13385 -1.20142)
				(xy -4.09448 -1.33096) (xy -4.0513 -1.45796) (xy -4.00304 -1.58496) (xy -3.95097 -1.70942) (xy -3.89509 -1.83261)
				(xy -3.83667 -1.95453) (xy -3.77317 -2.07391) (xy -3.70586 -2.19202) (xy -3.63474 -2.30632) (xy -3.56108 -2.41935)
				(xy -3.48361 -2.53111) (xy -3.40233 -2.63906) (xy -3.31724 -2.74447) (xy -3.22961 -2.84734) (xy -3.13817 -2.94767)
				(xy -3.04419 -3.04419) (xy -2.94767 -3.13817) (xy -2.84734 -3.22961) (xy -2.74447 -3.31724) (xy -2.63906 -3.40233)
				(xy -2.53111 -3.48361) (xy -2.41935 -3.56108) (xy -2.30632 -3.63474) (xy -2.19202 -3.70586) (xy -2.07391 -3.77317)
				(xy -1.95453 -3.83667) (xy -1.83261 -3.89509) (xy -1.70942 -3.95097) (xy -1.58496 -4.00304) (xy -1.45796 -4.0513)
				(xy -1.33096 -4.09448) (xy -1.20142 -4.13385) (xy -1.07061 -4.17068) (xy -0.9398 -4.20116) (xy -0.80645 -4.2291)
				(xy -0.6731 -4.25196) (xy -0.53975 -4.27101) (xy -0.40513 -4.28625) (xy -0.27051 -4.29641) (xy -0.13462 -4.30276)
				(xy 0 -4.3053) (xy 0.13462 -4.30276) (xy 0.27051 -4.29641) (xy 0.40513 -4.28625) (xy 0.53975 -4.27101)
				(xy 0.6731 -4.25196) (xy 0.80645 -4.2291) (xy 0.9398 -4.20116) (xy 1.07061 -4.17068) (xy 1.20142 -4.13385)
				(xy 1.33096 -4.09448) (xy 1.45796 -4.0513) (xy 1.58496 -4.00304) (xy 1.70942 -3.95097) (xy 1.83261 -3.89509)
				(xy 1.95453 -3.83667) (xy 2.07391 -3.77317) (xy 2.19202 -3.70586) (xy 2.30632 -3.63474) (xy 2.41935 -3.56108)
				(xy 2.53111 -3.48361) (xy 2.63906 -3.40233) (xy 2.74447 -3.31724) (xy 2.84734 -3.22961) (xy 2.94767 -3.13817)
				(xy 3.04419 -3.04419) (xy 3.13817 -2.94767) (xy 3.22961 -2.84734) (xy 3.31724 -2.74447) (xy 3.40233 -2.63906)
				(xy 3.48361 -2.53111) (xy 3.56108 -2.41935) (xy 3.63474 -2.30632) (xy 3.70586 -2.19202) (xy 3.77317 -2.07391)
				(xy 3.83667 -1.95453) (xy 3.89509 -1.83261) (xy 3.95097 -1.70942) (xy 4.00304 -1.58496) (xy 4.0513 -1.45796)
				(xy 4.09448 -1.33096) (xy 4.13385 -1.20142) (xy 4.17068 -1.07061) (xy 4.20116 -0.9398) (xy 4.2291 -0.80645)
				(xy 4.25196 -0.6731) (xy 4.27101 -0.53975) (xy 4.28625 -0.40513) (xy 4.29641 -0.27051) (xy 4.30276 -0.13462)
				(xy 4.3053 0) (xy 4.30276 0.13462) (xy 4.29641 0.27051) (xy 4.28625 0.40513) (xy 4.27101 0.53975)
				(xy 4.25196 0.6731) (xy 4.2291 0.80645) (xy 4.20116 0.9398) (xy 4.17068 1.07061) (xy 4.13385 1.20142)
				(xy 4.09448 1.33096) (xy 4.0513 1.45796) (xy 4.00304 1.58496) (xy 3.95097 1.70942) (xy 3.89509 1.83261)
				(xy 3.83667 1.95453) (xy 3.77317 2.07391) (xy 3.70586 2.19202) (xy 3.63474 2.30632) (xy 3.56108 2.41935)
				(xy 3.48361 2.53111) (xy 3.40233 2.63906) (xy 3.31724 2.74447) (xy 3.22961 2.84734) (xy 3.13817 2.94767)
				(xy 3.04419 3.04419) (xy 2.94767 3.13817) (xy 2.84734 3.22961) (xy 2.74447 3.31724) (xy 2.63906 3.40233)
				(xy 2.53111 3.48361) (xy 2.41935 3.56108) (xy 2.30632 3.63474) (xy 2.19202 3.70586) (xy 2.07391 3.77317)
				(xy 1.95453 3.83667) (xy 1.83261 3.89509) (xy 1.70942 3.95097) (xy 1.58496 4.00304) (xy 1.45796 4.0513)
				(xy 1.33096 4.09448) (xy 1.20142 4.13385) (xy 1.07061 4.17068) (xy 0.9398 4.20116) (xy 0.80645 4.2291)
				(xy 0.6731 4.25196) (xy 0.53975 4.27101) (xy 0.40513 4.28625) (xy 0.27051 4.29641) (xy 0.13462 4.30276)
			)
			(stroke
				(width 0)
				(type default)
			)
			(fill no)
			(layer "F.CrtYd")
		)
		(fp_poly
			(pts
				(xy 0 4.3053) (xy -0.13462 4.30276) (xy -0.27051 4.29641) (xy -0.40513 4.28625) (xy -0.53975 4.27101)
				(xy -0.6731 4.25196) (xy -0.80645 4.2291) (xy -0.9398 4.20116) (xy -1.07061 4.17068) (xy -1.20142 4.13385)
				(xy -1.33096 4.09448) (xy -1.45796 4.0513) (xy -1.58496 4.00304) (xy -1.70942 3.95097) (xy -1.83261 3.89509)
				(xy -1.95453 3.83667) (xy -2.07391 3.77317) (xy -2.19202 3.70586) (xy -2.30632 3.63474) (xy -2.41935 3.56108)
				(xy -2.53111 3.48361) (xy -2.63906 3.40233) (xy -2.74447 3.31724) (xy -2.84734 3.22961) (xy -2.94767 3.13817)
				(xy -3.04419 3.04419) (xy -3.13817 2.94767) (xy -3.22961 2.84734) (xy -3.31724 2.74447) (xy -3.40233 2.63906)
				(xy -3.48361 2.53111) (xy -3.56108 2.41935) (xy -3.63474 2.30632) (xy -3.70586 2.19202) (xy -3.77317 2.07391)
				(xy -3.83667 1.95453) (xy -3.89509 1.83261) (xy -3.95097 1.70942) (xy -4.00304 1.58496) (xy -4.0513 1.45796)
				(xy -4.09448 1.33096) (xy -4.13385 1.20142) (xy -4.17068 1.07061) (xy -4.20116 0.9398) (xy -4.2291 0.80645)
				(xy -4.25196 0.6731) (xy -4.27101 0.53975) (xy -4.28625 0.40513) (xy -4.29641 0.27051) (xy -4.30276 0.13462)
				(xy -4.3053 0) (xy -4.30276 -0.13462) (xy -4.29641 -0.27051) (xy -4.28625 -0.40513) (xy -4.27101 -0.53975)
				(xy -4.25196 -0.6731) (xy -4.2291 -0.80645) (xy -4.20116 -0.9398) (xy -4.17068 -1.07061) (xy -4.13385 -1.20142)
				(xy -4.09448 -1.33096) (xy -4.0513 -1.45796) (xy -4.00304 -1.58496) (xy -3.95097 -1.70942) (xy -3.89509 -1.83261)
				(xy -3.83667 -1.95453) (xy -3.77317 -2.07391) (xy -3.70586 -2.19202) (xy -3.63474 -2.30632) (xy -3.56108 -2.41935)
				(xy -3.48361 -2.53111) (xy -3.40233 -2.63906) (xy -3.31724 -2.74447) (xy -3.22961 -2.84734) (xy -3.13817 -2.94767)
				(xy -3.04419 -3.04419) (xy -2.94767 -3.13817) (xy -2.84734 -3.22961) (xy -2.74447 -3.31724) (xy -2.63906 -3.40233)
				(xy -2.53111 -3.48361) (xy -2.41935 -3.56108) (xy -2.30632 -3.63474) (xy -2.19202 -3.70586) (xy -2.07391 -3.77317)
				(xy -1.95453 -3.83667) (xy -1.83261 -3.89509) (xy -1.70942 -3.95097) (xy -1.58496 -4.00304) (xy -1.45796 -4.0513)
				(xy -1.33096 -4.09448) (xy -1.20142 -4.13385) (xy -1.07061 -4.17068) (xy -0.9398 -4.20116) (xy -0.80645 -4.2291)
				(xy -0.6731 -4.25196) (xy -0.53975 -4.27101) (xy -0.40513 -4.28625) (xy -0.27051 -4.29641) (xy -0.13462 -4.30276)
				(xy 0 -4.3053) (xy 0.13462 -4.30276) (xy 0.27051 -4.29641) (xy 0.40513 -4.28625) (xy 0.53975 -4.27101)
				(xy 0.6731 -4.25196) (xy 0.80645 -4.2291) (xy 0.9398 -4.20116) (xy 1.07061 -4.17068) (xy 1.20142 -4.13385)
				(xy 1.33096 -4.09448) (xy 1.45796 -4.0513) (xy 1.58496 -4.00304) (xy 1.70942 -3.95097) (xy 1.83261 -3.89509)
				(xy 1.95453 -3.83667) (xy 2.07391 -3.77317) (xy 2.19202 -3.70586) (xy 2.30632 -3.63474) (xy 2.41935 -3.56108)
				(xy 2.53111 -3.48361) (xy 2.63906 -3.40233) (xy 2.74447 -3.31724) (xy 2.84734 -3.22961) (xy 2.94767 -3.13817)
				(xy 3.04419 -3.04419) (xy 3.13817 -2.94767) (xy 3.22961 -2.84734) (xy 3.31724 -2.74447) (xy 3.40233 -2.63906)
				(xy 3.48361 -2.53111) (xy 3.56108 -2.41935) (xy 3.63474 -2.30632) (xy 3.70586 -2.19202) (xy 3.77317 -2.07391)
				(xy 3.83667 -1.95453) (xy 3.89509 -1.83261) (xy 3.95097 -1.70942) (xy 4.00304 -1.58496) (xy 4.0513 -1.45796)
				(xy 4.09448 -1.33096) (xy 4.13385 -1.20142) (xy 4.17068 -1.07061) (xy 4.20116 -0.9398) (xy 4.2291 -0.80645)
				(xy 4.25196 -0.6731) (xy 4.27101 -0.53975) (xy 4.28625 -0.40513) (xy 4.29641 -0.27051) (xy 4.30276 -0.13462)
				(xy 4.3053 0) (xy 4.30276 0.13462) (xy 4.29641 0.27051) (xy 4.28625 0.40513) (xy 4.27101 0.53975)
				(xy 4.25196 0.6731) (xy 4.2291 0.80645) (xy 4.20116 0.9398) (xy 4.17068 1.07061) (xy 4.13385 1.20142)
				(xy 4.09448 1.33096) (xy 4.0513 1.45796) (xy 4.00304 1.58496) (xy 3.95097 1.70942) (xy 3.89509 1.83261)
				(xy 3.83667 1.95453) (xy 3.77317 2.07391) (xy 3.70586 2.19202) (xy 3.63474 2.30632) (xy 3.56108 2.41935)
				(xy 3.48361 2.53111) (xy 3.40233 2.63906) (xy 3.31724 2.74447) (xy 3.22961 2.84734) (xy 3.13817 2.94767)
				(xy 3.04419 3.04419) (xy 2.94767 3.13817) (xy 2.84734 3.22961) (xy 2.74447 3.31724) (xy 2.63906 3.40233)
				(xy 2.53111 3.48361) (xy 2.41935 3.56108) (xy 2.30632 3.63474) (xy 2.19202 3.70586) (xy 2.07391 3.77317)
				(xy 1.95453 3.83667) (xy 1.83261 3.89509) (xy 1.70942 3.95097) (xy 1.58496 4.00304) (xy 1.45796 4.0513)
				(xy 1.33096 4.09448) (xy 1.20142 4.13385) (xy 1.07061 4.17068) (xy 0.9398 4.20116) (xy 0.80645 4.2291)
				(xy 0.6731 4.25196) (xy 0.53975 4.27101) (xy 0.40513 4.28625) (xy 0.27051 4.29641) (xy 0.13462 4.30276)
			)
			(stroke
				(width 0)
				(type default)
			)
			(fill no)
			(layer "F.Fab")
		)
		(pad "1" thru_hole circle
			(at 0 0)
			(size 8.001 8.001)
			(drill 3.5052)
			(layers "*.Cu" "*.Mask")
			(remove_unused_layers no)
			(net "GND")
			(clearance -1.7399)
			(thermal_gap 0.3048)
			(padstack
				(mode front_inner_back)
				(layer "Inner"
					(shape circle)
					(size 3.9116 3.9116)
					(clearance 0.3048)
				)
				(layer "B.Cu"
					(shape circle)
					(size 8.001 8.001)
					(clearance -1.7399)
				)
			)
		)
	)
	(footprint ""
		(layer "F.Cu")
		(at 42.418 -371.221)
		(property "Reference" "PR43"
			(at 0 0 0)
			(layer "F.SilkS")
			(hide yes)
			(effects
				(font
					(size 1.27 1.27)
				)
			)
		)
		(property "Value" "1K5R5J-GP"
			(at 0 -8.9535 0)
			(unlocked yes)
			(layer "F.Fab")
			(hide yes)
			(effects
				(font
					(size 1.27 1.016)
					(thickness 0.1524)
				)
			)
		)
		(property "Device Type" "R805H24"
			(at 0 -10.6299 0)
			(unlocked yes)
			(layer "F.Fab")
			(hide yes)
			(effects
				(font
					(size 1.27 1.016)
					(thickness 0.1524)
				)
			)
		)
		(duplicate_pad_numbers_are_jumpers no)
		(fp_line
			(start -0.889 -1.7018)
			(end -0.889 0.2794)
			(stroke
				(width 0.1524)
				(type default)
			)
			(layer "F.SilkS")
		)
		(fp_line
			(start -0.889 0.0762)
			(end -0.889 1.7018)
			(stroke
				(width 0.1524)
				(type default)
			)
			(layer "F.SilkS")
		)
		(fp_line
			(start -0.889 1.7018)
			(end 0.889 1.7018)
			(stroke
				(width 0.1524)
				(type default)
			)
			(layer "F.SilkS")
		)
		(fp_line
			(start 0.889 -1.7018)
			(end -0.889 -1.7018)
			(stroke
				(width 0.1524)
				(type default)
			)
			(layer "F.SilkS")
		)
		(fp_line
			(start 0.889 -1.7018)
			(end 0.889 -0.381)
			(stroke
				(width 0.1524)
				(type default)
			)
			(layer "F.SilkS")
		)
		(fp_line
			(start 0.889 1.7018)
			(end 0.889 -0.508)
			(stroke
				(width 0.1524)
				(type default)
			)
			(layer "F.SilkS")
		)
		(fp_poly
			(pts
				(xy 0.9652 -1.778) (xy 0.9652 1.778) (xy -0.9652 1.778) (xy -0.9652 -1.778)
			)
			(stroke
				(width 0)
				(type default)
			)
			(fill no)
			(layer "F.CrtYd")
		)
		(fp_rect
			(start -0.9652 1.778)
			(end 0.9652 -1.778)
			(stroke
				(width 0)
				(type default)
			)
			(fill no)
			(layer "F.Fab")
		)
		(pad "1" smd rect
			(at 0 -0.9652)
			(size 1.397 1.143)
			(layers "F.Cu" "F.Mask" "F.Paste")
			(net "P12V_AUX")
		)
		(pad "2" smd rect
			(at 0 0.9652)
			(size 1.397 1.143)
			(layers "F.Cu" "F.Mask" "F.Paste")
			(net "ADM1276_EN_NET")
		)
	)
	(footprint ""
		(layer "F.Cu")
		(at 31.7246 -149.073616)
		(property "Reference" "R128"
			(at 0 0 0)
			(layer "F.SilkS")
			(hide yes)
			(effects
				(font
					(size 1.27 1.27)
				)
			)
		)
		(property "Value" "10KR2F-2-GP"
			(at 0.064008 -3.993896 0)
			(unlocked yes)
			(layer "F.Fab")
			(hide yes)
			(effects
				(font
					(size 1.016 1.016)
					(thickness 0.1524)
				)
			)
		)
		(property "Device Type" "R402H16"
			(at 0.064008 -5.517896 0)
			(unlocked yes)
			(layer "F.Fab")
			(hide yes)
			(effects
				(font
					(size 1.016 1.016)
					(thickness 0.1524)
				)
			)
		)
		(duplicate_pad_numbers_are_jumpers no)
		(fp_line
			(start -0.508 -0.9398)
			(end -0.508 0.9398)
			(stroke
				(width 0.1524)
				(type default)
			)
			(layer "F.SilkS")
		)
		(fp_line
			(start 0.508 -0.9398)
			(end -0.508 -0.9398)
			(stroke
				(width 0.1524)
				(type default)
			)
			(layer "F.SilkS")
		)
		(fp_rect
			(start -0.508 0.9398)
			(end 0.508 -0.9398)
			(stroke
				(width 0)
				(type default)
			)
			(fill no)
			(layer "F.CrtYd")
		)
		(fp_rect
			(start -0.508 0.9398)
			(end 0.508 -0.9398)
			(stroke
				(width 0)
				(type default)
			)
			(fill no)
			(layer "F.Fab")
		)
		(pad "1" smd custom
			(at 0 -0.4445)
			(size 0.1397 0.1397)
			(layers "F.Cu" "F.Mask" "F.Paste")
			(net "NCT7904_VSEN7")
			(options
				(clearance outline)
				(anchor circle)
			)
			(primitives
				(gr_poly
					(pts
						(arc
							(start -0.1778 -0.2794)
							(mid -0.249642 -0.249642)
							(end -0.2794 -0.1778)
						)
						(arc
							(start -0.2794 0.1778)
							(mid -0.249642 0.249642)
							(end -0.1778 0.2794)
						)
						(arc
							(start 0.1778 0.2794)
							(mid 0.249642 0.249642)
							(end 0.2794 0.1778)
						)
						(arc
							(start 0.2794 -0.1778)
							(mid 0.249642 -0.249642)
							(end 0.1778 -0.2794)
						)
					)
					(width 0)
					(fill yes)
				)
			)
		)
		(pad "2" smd custom
			(at 0 0.4445)
			(size 0.1397 0.1397)
			(layers "F.Cu" "F.Mask" "F.Paste")
			(net "GND")
			(options
				(clearance outline)
				(anchor circle)
			)
			(primitives
				(gr_poly
					(pts
						(arc
							(start -0.1778 -0.2794)
							(mid -0.249642 -0.249642)
							(end -0.2794 -0.1778)
						)
						(arc
							(start -0.2794 0.1778)
							(mid -0.249642 0.249642)
							(end -0.1778 0.2794)
						)
						(arc
							(start 0.1778 0.2794)
							(mid 0.249642 0.249642)
							(end 0.2794 0.1778)
						)
						(arc
							(start 0.2794 -0.1778)
							(mid 0.249642 -0.249642)
							(end 0.1778 -0.2794)
						)
					)
					(width 0)
					(fill yes)
				)
			)
		)
	)
	(footprint ""
		(layer "F.Cu")
		(at 41.8084 -155.0162 180)
		(property "Reference" "C4"
			(at 0 0 180)
			(layer "F.SilkS")
			(hide yes)
			(effects
				(font
					(size 1.27 1.27)
				)
			)
		)
		(property "Value" "SCD1U16V2KX-3GP"
			(at 1.1811 -2.7051 180)
			(unlocked yes)
			(layer "F.Fab")
			(hide yes)
			(effects
				(font
					(size 1.016 1.016)
					(thickness 0.1524)
				)
			)
		)
		(property "Device Type" "C402H22"
			(at 1.1811 -4.2291 180)
			(unlocked yes)
			(layer "F.Fab")
			(hide yes)
			(effects
				(font
					(size 1.016 1.016)
					(thickness 0.1524)
				)
			)
		)
		(duplicate_pad_numbers_are_jumpers no)
		(fp_rect
			(start -0.4318 0.9525)
			(end 0.4318 -0.9525)
			(stroke
				(width 0)
				(type default)
			)
			(fill no)
			(layer "F.CrtYd")
		)
		(fp_rect
			(start -0.4318 0.9525)
			(end 0.4318 -0.9525)
			(stroke
				(width 0)
				(type default)
			)
			(fill no)
			(layer "F.Fab")
		)
		(pad "1" smd custom
			(at 0 -0.4445 180)
			(size 0.1524 0.1524)
			(layers "F.Cu" "F.Mask" "F.Paste")
			(net "NCT7904_3VSB")
			(options
				(clearance outline)
				(anchor circle)
			)
			(primitives
				(gr_poly
					(pts
						(arc
							(start 0.3048 -0.2032)
							(mid 0.275042 -0.275042)
							(end 0.2032 -0.3048)
						)
						(arc
							(start -0.2032 -0.3048)
							(mid -0.275042 -0.275042)
							(end -0.3048 -0.2032)
						)
						(arc
							(start -0.3048 0.2032)
							(mid -0.275042 0.275042)
							(end -0.2032 0.3048)
						)
						(arc
							(start 0.2032 0.3048)
							(mid 0.275042 0.275042)
							(end 0.3048 0.2032)
						)
					)
					(width 0)
					(fill yes)
				)
			)
		)
		(pad "2" smd custom
			(at 0 0.4445 180)
			(size 0.1524 0.1524)
			(layers "F.Cu" "F.Mask" "F.Paste")
			(net "GND")
			(options
				(clearance outline)
				(anchor circle)
			)
			(primitives
				(gr_poly
					(pts
						(arc
							(start 0.3048 -0.2032)
							(mid 0.275042 -0.275042)
							(end 0.2032 -0.3048)
						)
						(arc
							(start -0.2032 -0.3048)
							(mid -0.275042 -0.275042)
							(end -0.3048 -0.2032)
						)
						(arc
							(start -0.3048 0.2032)
							(mid -0.275042 0.275042)
							(end -0.2032 0.3048)
						)
						(arc
							(start 0.2032 0.3048)
							(mid 0.275042 0.275042)
							(end 0.3048 0.2032)
						)
					)
					(width 0)
					(fill yes)
				)
			)
		)
	)
)
